(kicad_pcb
	(version 20260206)
	(generator "pcbnew")
	(generator_version "10.0")
	(general
		(thickness 1.21888)
		(legacy_teardrops no)
	)
	(paper "A4")
	(title_block
		(title "timecard-v7 — TimeCard-DC-V7_EXP.PcbDoc")
		(comment 1 "Time Appliance Project (Time Card) / footprints 48-55 of 160")
	)
	(layers
		(0 "F.Cu" signal "TOP")
		(4 "In1.Cu" signal "SGND")
		(6 "In2.Cu" signal "IN1")
		(8 "In3.Cu" signal "IN2")
		(10 "In4.Cu" signal "SGND1")
		(2 "B.Cu" signal "BOTTOM")
		(9 "F.Adhes" user "F.Adhesive")
		(11 "B.Adhes" user "B.Adhesive")
		(13 "F.Paste" user "Top Paste")
		(15 "B.Paste" user "Bottom Paste")
		(5 "F.SilkS" user "Top Overlay")
		(7 "B.SilkS" user "Bottom Overlay")
		(1 "F.Mask" user "Top Solder")
		(3 "B.Mask" user "Bottom Solder")
		(17 "Dwgs.User" user "User.Drawings")
		(19 "Cmts.User" user "User.Comments")
		(21 "Eco1.User" user "User.Eco1")
		(23 "Eco2.User" user "User.Eco2")
		(25 "Edge.Cuts" user)
		(27 "Margin" user)
		(31 "F.CrtYd" user "Top Courtyard")
		(29 "B.CrtYd" user "Bottom Courtyard")
		(35 "F.Fab" user "Top Component Center")
		(33 "B.Fab" user "Bottom Component Center")
	)
	(footprint "Resistors:RESC2012X50N"
		(layer "F.Cu")
		(at 229.5261 142.1162 -90)
		(property "Reference" "R20"
			(at -1.2 -1.506655 270)
			(unlocked yes)
			(layer "F.SilkS")
			(effects
				(font
					(size 0.762 0.762)
					(thickness 0.2286)
				)
				(justify left bottom)
			)
		)
		(property "Value" "CRCW080533R0FKEA"
			(at -7.93582 -4.5751 0)
			(unlocked yes)
			(layer "F.SilkS")
			(hide yes)
			(effects
				(font
					(size 1.524 1.524)
					(thickness 0.254)
				)
				(justify left bottom)
			)
		)
		(sheetname "PCIe_JTAG")
		(sheetfile "PCIe_JTAG.kicad_sch")
		(duplicate_pad_numbers_are_jumpers no)
		(fp_line
			(start 0 0.762)
			(end 0 -0.762)
			(stroke
				(width 0.1524)
				(type solid)
			)
			(layer "F.SilkS")
		)
		(pad "1" smd rect
			(at -1 0)
			(size 1.45 0.95)
			(layers "F.Cu" "F.Mask" "F.Paste")
			(net "FPGA_TMS")
		)
		(pad "2" smd rect
			(at 1 0)
			(size 1.45 0.95)
			(layers "F.Cu" "F.Mask" "F.Paste")
			(net "NetR20_2")
		)
	)
	(footprint "Vault:RESC1608X55X25NL10T15"
		(layer "F.Cu")
		(at 77.8761 121.8662 180)
		(property "Reference" "R28"
			(at 0.81672 1.068825 0)
			(unlocked yes)
			(layer "F.SilkS")
			(effects
				(font
					(size 0.762 0.762)
					(thickness 0.2286)
				)
				(justify left bottom)
			)
		)
		(property "Value" "49.9R"
			(at 1.1445 -4.42999 0)
			(unlocked yes)
			(layer "F.SilkS")
			(hide yes)
			(effects
				(font
					(size 1.524 1.524)
					(thickness 0.254)
				)
				(justify left bottom)
			)
		)
		(sheetname "USER_IO")
		(sheetfile "USER_IO.kicad_sch")
		(duplicate_pad_numbers_are_jumpers no)
		(pad "1" smd rect
			(at -0.7 0 270)
			(size 0.9 0.7)
			(layers "F.Cu" "F.Mask" "F.Paste")
			(net "NetR28_1")
		)
		(pad "2" smd rect
			(at 0.7 0 270)
			(size 0.9 0.7)
			(layers "F.Cu" "F.Mask" "F.Paste")
			(net "NetAN3_1")
		)
	)
	(footprint "Vault:TECO-1909763-1_V"
		(layer "F.Cu")
		(at 74.3761 121.8662 -90)
		(property "Reference" "J3"
			(at -2.973069 1.271395 0)
			(unlocked yes)
			(layer "F.SilkS")
			(effects
				(font
					(size 0.762 0.762)
					(thickness 0.2286)
				)
			)
		)
		(property "Value" "1909763-1"
			(at 4.608085 3.749802 270)
			(unlocked yes)
			(layer "F.SilkS")
			(hide yes)
			(effects
				(font
					(size 1.524 1.524)
					(thickness 0.254)
				)
			)
		)
		(sheetname "USER_IO")
		(sheetfile "USER_IO.kicad_sch")
		(duplicate_pad_numbers_are_jumpers no)
		(fp_line
			(start 0.55 -1.3)
			(end -0.55 -1.3)
			(stroke
				(width 0.2)
				(type solid)
			)
			(layer "F.SilkS")
		)
		(fp_circle
			(center -1.778 1.65)
			(end -1.903 1.65)
			(stroke
				(width 0.25)
				(type solid)
			)
			(fill no)
			(layer "F.SilkS")
		)
		(pad "1" smd rect
			(at -1.475 0 270)
			(size 1.05 2.2)
			(layers "F.Cu" "F.Mask" "F.Paste")
			(net "GND")
		)
		(pad "2" smd rect
			(at 0 1.525 270)
			(size 1 1.05)
			(layers "F.Cu" "F.Mask" "F.Paste")
			(net "NetAN3_1")
		)
		(pad "3" smd rect
			(at 1.475 0 270)
			(size 1.05 2.2)
			(layers "F.Cu" "F.Mask" "F.Paste")
			(net "GND")
		)
	)
	(footprint "Vault:CAPC1608X87X45ML20T05"
		(layer "F.Cu")
		(at 92.1261 74.5786 90)
		(property "Reference" "C59"
			(at -4.25 1.343345 90)
			(unlocked yes)
			(layer "F.SilkS")
			(effects
				(font
					(size 0.762 0.762)
					(thickness 0.2286)
				)
				(justify left bottom)
			)
		)
		(property "Value" "0.1uF"
			(at -3.47599 -0.2921 0)
			(unlocked yes)
			(layer "F.SilkS")
			(hide yes)
			(effects
				(font
					(size 1.524 1.524)
					(thickness 0.254)
				)
				(justify left bottom)
			)
		)
		(sheetname "GPS_IMU_SENSORS")
		(sheetfile "GPS_IMU_SENSORS.kicad_sch")
		(duplicate_pad_numbers_are_jumpers no)
		(pad "1" smd rect
			(at -0.7 0 180)
			(size 1.1 1.05)
			(layers "F.Cu" "F.Mask" "F.Paste")
			(net "GND")
		)
		(pad "2" smd rect
			(at 0.7 0 180)
			(size 1.1 1.05)
			(layers "F.Cu" "F.Mask" "F.Paste")
			(net "+3.3V")
		)
	)
	(footprint "Vault:CAPC1608X87X45ML20T05"
		(layer "F.Cu")
		(at 80.6261 112.1162 -90)
		(property "Reference" "C28"
			(at 2.7714 -0.026931 90)
			(unlocked yes)
			(layer "F.SilkS")
			(effects
				(font
					(size 0.762 0.762)
					(thickness 0.2286)
				)
			)
		)
		(property "Value" "0.1uF"
			(at 2.09443 2.657602 270)
			(unlocked yes)
			(layer "F.SilkS")
			(hide yes)
			(effects
				(font
					(size 1.524 1.524)
					(thickness 0.254)
				)
			)
		)
		(sheetname "USER_IO")
		(sheetfile "USER_IO.kicad_sch")
		(duplicate_pad_numbers_are_jumpers no)
		(pad "1" smd rect
			(at -0.7 0)
			(size 1.1 1.05)
			(layers "F.Cu" "F.Mask" "F.Paste")
			(net "+3.3V")
		)
		(pad "2" smd rect
			(at 0.7 0)
			(size 1.1 1.05)
			(layers "F.Cu" "F.Mask" "F.Paste")
			(net "GND")
		)
	)
	(footprint "Vault:CAPC1608X87X45ML20T05"
		(layer "F.Cu")
		(at 197.3761 84.2786 -90)
		(property "Reference" "C31"
			(at 2.721395 -0.026921 90)
			(unlocked yes)
			(layer "F.SilkS")
			(effects
				(font
					(size 0.762 0.762)
					(thickness 0.2286)
				)
			)
		)
		(property "Value" "0.1uF"
			(at 2.09443 2.657602 270)
			(unlocked yes)
			(layer "F.SilkS")
			(hide yes)
			(effects
				(font
					(size 1.524 1.524)
					(thickness 0.254)
				)
			)
		)
		(sheetname "GPS_IMU_SENSORS")
		(sheetfile "GPS_IMU_SENSORS.kicad_sch")
		(duplicate_pad_numbers_are_jumpers no)
		(pad "1" smd rect
			(at -0.7 0)
			(size 1.1 1.05)
			(layers "F.Cu" "F.Mask" "F.Paste")
			(net "GND")
		)
		(pad "2" smd rect
			(at 0.7 0)
			(size 1.1 1.05)
			(layers "F.Cu" "F.Mask" "F.Paste")
			(net "+3.3V")
		)
	)
	(footprint "Vault:CAPC1608X90X35NL10T15"
		(layer "F.Cu")
		(at 206.3347 83.4132)
		(property "Reference" "C22"
			(at 1.479 0.396345 0)
			(unlocked yes)
			(layer "F.SilkS")
			(effects
				(font
					(size 0.762 0.762)
					(thickness 0.2286)
				)
				(justify left bottom)
			)
		)
		(property "Value" "0.033uF"
			(at 17.9043 13.68639 0)
			(unlocked yes)
			(layer "F.SilkS")
			(hide yes)
			(effects
				(font
					(size 1.524 1.524)
					(thickness 0.254)
				)
				(justify left bottom)
			)
		)
		(sheetname "POWER")
		(sheetfile "POWER.kicad_sch")
		(duplicate_pad_numbers_are_jumpers no)
		(pad "1" smd rect
			(at -0.675 0 90)
			(size 0.95 0.85)
			(layers "F.Cu" "F.Mask" "F.Paste")
			(net "NetC22_1")
		)
		(pad "2" smd rect
			(at 0.675 0 90)
			(size 0.95 0.85)
			(layers "F.Cu" "F.Mask" "F.Paste")
			(net "NetC22_2")
		)
	)
	(footprint "Vault:FP-LTST-C191TBKT-MFG"
		(layer "F.Cu")
		(at 69.8761 52.1162 90)
		(property "Reference" "D3"
			(at -6.771395 0.026921 90)
			(unlocked yes)
			(layer "F.SilkS")
			(effects
				(font
					(size 0.762 0.762)
					(thickness 0.2286)
				)
			)
		)
		(property "Value" "BLUE"
			(at 1.307195 2.479802 90)
			(unlocked yes)
			(layer "F.SilkS")
			(hide yes)
			(effects
				(font
					(size 1.524 1.524)
					(thickness 0.254)
				)
			)
		)
		(sheetname "USER_IO_STATUS")
		(sheetfile "USER_IO_STATUS.kicad_sch")
		(duplicate_pad_numbers_are_jumpers no)
		(fp_line
			(start -0.85 -0.8)
			(end 0.85 -0.8)
			(stroke
				(width 0.2)
				(type solid)
			)
			(layer "F.SilkS")
		)
		(fp_line
			(start -0.85 0.8)
			(end 0.85 0.8)
			(stroke
				(width 0.2)
				(type solid)
			)
			(layer "F.SilkS")
		)
		(fp_circle
			(center -1.75 0)
			(end -1.625 0)
			(stroke
				(width 0.25)
				(type solid)
			)
			(fill no)
			(layer "F.SilkS")
		)
		(fp_line
			(start 1.25 -0.55)
			(end 1.25 0.55)
			(stroke
				(width 0.2)
				(type solid)
			)
			(layer "F.CrtYd")
		)
		(fp_line
			(start -1.25 -0.55)
			(end 1.25 -0.55)
			(stroke
				(width 0.2)
				(type solid)
			)
			(layer "F.CrtYd")
		)
		(fp_line
			(start -1.25 -0.55)
			(end -1.25 0.55)
			(stroke
				(width 0.2)
				(type solid)
			)
			(layer "F.CrtYd")
		)
		(fp_line
			(start -1.25 0.55)
			(end 1.25 0.55)
			(stroke
				(width 0.2)
				(type solid)
			)
			(layer "F.CrtYd")
		)
		(fp_line
			(start 1.25 -0.55)
			(end 1.25 0.55)
			(stroke
				(width 0.2)
				(type solid)
			)
			(layer "F.Fab")
		)
		(fp_line
			(start -1.25 -0.55)
			(end 1.25 -0.55)
			(stroke
				(width 0.2)
				(type solid)
			)
			(layer "F.Fab")
		)
		(fp_line
			(start -1.25 -0.55)
			(end -1.25 0.55)
			(stroke
				(width 0.2)
				(type solid)
			)
			(layer "F.Fab")
		)
		(fp_line
			(start 0 -0.5)
			(end 0 0.5)
			(stroke
				(width 0.1)
				(type solid)
			)
			(layer "F.Fab")
		)
		(fp_line
			(start -0.5 0)
			(end 0.5 0)
			(stroke
				(width 0.1)
				(type solid)
			)
			(layer "F.Fab")
		)
		(fp_line
			(start -1.25 0.55)
			(end 1.25 0.55)
			(stroke
				(width 0.2)
				(type solid)
			)
			(layer "F.Fab")
		)
		(fp_text user "${REFERENCE}"
			(at 0 0.28424 90)
			(unlocked yes)
			(layer "F.Fab")
			(effects
				(font
					(face "Arial")
					(size 0.63 0.63)
					(thickness 0.1)
				)
				(justify left bottom)
			)
		)
		(pad "1" smd rect
			(at -0.75 0 90)
			(size 0.8 0.8)
			(layers "F.Cu" "F.Mask" "F.Paste")
			(net "NetD3_1")
			(solder_mask_margin 0)
			(solder_paste_margin 0)
		)
		(pad "2" smd rect
			(at 0.75 0 90)
			(size 0.8 0.8)
			(layers "F.Cu" "F.Mask" "F.Paste")
			(net "+3.3V")
			(solder_mask_margin 0)
			(solder_paste_margin 0)
		)
	)
)
